(kicad_pcb
	(version 20260206)
	(generator "pcbnew")
	(generator_version "10.0")
	(general
		(thickness 1.6)
		(legacy_teardrops no)
	)
	(paper "A4")
	(title_block
		(title "03242023_DA0F0TMBIJ0_F0T_Motherboard_J_brd_V01_OCP.brd")
		(comment 1 "Grand Teton / footprints 1608-1614 of 6105")
	)
	(layers
		(0 "F.Cu" signal "TOP")
		(4 "In1.Cu" signal "GND")
		(6 "In2.Cu" signal "IN1")
		(8 "In3.Cu" signal "GND1")
		(10 "In4.Cu" signal "IN2")
		(12 "In5.Cu" signal "GND2")
		(14 "In6.Cu" signal "IN3")
		(16 "In7.Cu" signal "GND3")
		(18 "In8.Cu" signal "VCC")
		(20 "In9.Cu" signal "VCC1")
		(22 "In10.Cu" signal "GND4")
		(24 "In11.Cu" signal "IN4")
		(26 "In12.Cu" signal "GND5")
		(28 "In13.Cu" signal "IN5")
		(30 "In14.Cu" signal "GND6")
		(32 "In15.Cu" signal "IN6")
		(34 "In16.Cu" signal "GND7")
		(2 "B.Cu" signal "BOTTOM")
		(9 "F.Adhes" user "F.Adhesive")
		(11 "B.Adhes" user "B.Adhesive")
		(13 "F.Paste" user "Package Geometry/Pastemask Top")
		(15 "B.Paste" user "Package Geometry/Pastemask Bottom")
		(5 "F.SilkS" user "Ref Des/Silkscreen Top")
		(7 "B.SilkS" user "Ref Des/Silkscreen Bottom")
		(1 "F.Mask" user "Board Geometry/Soldermask Top")
		(3 "B.Mask" user "Board Geometry/Soldermask Bottom")
		(17 "Dwgs.User" user "User.Drawings")
		(19 "Cmts.User" user "User.Comments")
		(21 "Eco1.User" user "User.Eco1")
		(23 "Eco2.User" user "User.Eco2")
		(25 "Edge.Cuts" user "Board Geometry/Outline")
		(27 "Margin" user)
		(31 "F.CrtYd" user "Package Geometry/Place Bound Top")
		(29 "B.CrtYd" user "Package Geometry/Place Bound Bottom")
		(35 "F.Fab" user "Ref Des/Assembly Top")
		(33 "B.Fab" user "Ref Des/Assembly Bottom")
	)
	(footprint ""
		(layer "F.Cu")
		(at 162.212274 -408.517344 -90)
		(property "Reference" "C1543"
			(at 0 0 270)
			(layer "F.SilkS")
			(hide yes)
			(effects
				(font
					(size 1.27 1.27)
				)
			)
		)
		(property "Value" ""
			(at 0 0 270)
			(layer "F.Fab")
			(effects
				(font
					(size 1.27 1.27)
				)
			)
		)
		(duplicate_pad_numbers_are_jumpers no)
		(fp_line
			(start -0.299974 0.150114)
			(end -0.299974 -0.150114)
			(stroke
				(width 0.1)
				(type default)
			)
			(layer "F.Fab")
		)
		(fp_line
			(start 0.299974 0.150114)
			(end -0.299974 0.150114)
			(stroke
				(width 0.1)
				(type default)
			)
			(layer "F.Fab")
		)
		(fp_line
			(start -0.299974 -0.150114)
			(end 0.299974 -0.150114)
			(stroke
				(width 0.1)
				(type default)
			)
			(layer "F.Fab")
		)
		(fp_line
			(start 0.299974 -0.150114)
			(end 0.299974 0.150114)
			(stroke
				(width 0.1)
				(type default)
			)
			(layer "F.Fab")
		)
		(pad "1" smd rect
			(at -0.2667 0 270)
			(size 0.3048 0.381)
			(layers "F.Cu" "F.Mask" "F.Paste")
			(net "P5E_CPU1_PE3_TX_C_DP<2>")
		)
		(pad "2" smd rect
			(at 0.2667 0 270)
			(size 0.3048 0.381)
			(layers "F.Cu" "F.Mask" "F.Paste")
			(net "P5E_CPU1_PE3_TX_DP<2>")
		)
	)
	(footprint ""
		(layer "F.Cu")
		(at 355.233478 -238.162338 -90)
		(property "Reference" "C1043"
			(at 0 0 270)
			(layer "F.SilkS")
			(hide yes)
			(effects
				(font
					(size 1.27 1.27)
				)
			)
		)
		(property "Value" ""
			(at 0 0 270)
			(layer "F.Fab")
			(effects
				(font
					(size 1.27 1.27)
				)
			)
		)
		(duplicate_pad_numbers_are_jumpers no)
		(fp_line
			(start -0.7874 0.4064)
			(end -0.7874 -0.4064)
			(stroke
				(width 0.1524)
				(type default)
			)
			(layer "F.SilkS")
		)
		(fp_line
			(start 0.7874 0.4064)
			(end -0.7874 0.4064)
			(stroke
				(width 0.1524)
				(type default)
			)
			(layer "F.SilkS")
		)
		(fp_line
			(start -0.7874 -0.4064)
			(end 0.7874 -0.4064)
			(stroke
				(width 0.1524)
				(type default)
			)
			(layer "F.SilkS")
		)
		(fp_line
			(start 0.7874 -0.4064)
			(end 0.7874 0.4064)
			(stroke
				(width 0.1524)
				(type default)
			)
			(layer "F.SilkS")
		)
		(fp_line
			(start -0.67945 0.3048)
			(end -0.67945 -0.305054)
			(stroke
				(width 0.1)
				(type default)
			)
			(layer "F.Fab")
		)
		(fp_line
			(start -0.12065 0.3048)
			(end -0.67945 0.3048)
			(stroke
				(width 0.1)
				(type default)
			)
			(layer "F.Fab")
		)
		(fp_line
			(start 0.120396 0.3048)
			(end 0.120396 0.2794)
			(stroke
				(width 0.1)
				(type default)
			)
			(layer "F.Fab")
		)
		(fp_line
			(start 0.67945 0.3048)
			(end 0.120396 0.3048)
			(stroke
				(width 0.1)
				(type default)
			)
			(layer "F.Fab")
		)
		(fp_line
			(start -0.12065 0.2794)
			(end -0.12065 0.3048)
			(stroke
				(width 0.1)
				(type default)
			)
			(layer "F.Fab")
		)
		(fp_line
			(start 0.120396 0.2794)
			(end -0.12065 0.2794)
			(stroke
				(width 0.1)
				(type default)
			)
			(layer "F.Fab")
		)
		(fp_line
			(start -0.12065 -0.2794)
			(end 0.12065 -0.2794)
			(stroke
				(width 0.1)
				(type default)
			)
			(layer "F.Fab")
		)
		(fp_line
			(start 0.12065 -0.2794)
			(end 0.12065 -0.3048)
			(stroke
				(width 0.1)
				(type default)
			)
			(layer "F.Fab")
		)
		(fp_line
			(start 0.12065 -0.3048)
			(end 0.67945 -0.3048)
			(stroke
				(width 0.1)
				(type default)
			)
			(layer "F.Fab")
		)
		(fp_line
			(start 0.67945 -0.3048)
			(end 0.67945 0.3048)
			(stroke
				(width 0.1)
				(type default)
			)
			(layer "F.Fab")
		)
		(fp_line
			(start -0.67945 -0.305054)
			(end -0.12065 -0.305054)
			(stroke
				(width 0.1)
				(type default)
			)
			(layer "F.Fab")
		)
		(fp_line
			(start -0.12065 -0.305054)
			(end -0.12065 -0.2794)
			(stroke
				(width 0.1)
				(type default)
			)
			(layer "F.Fab")
		)
		(pad "1" smd circle
			(at -0.40005 0 270)
			(size 0 0)
			(layers "F.Cu" "F.Mask" "F.Paste")
			(net "PVCCIN_CPU0")
		)
		(pad "2" smd circle
			(at 0.40005 0 270)
			(size 0 0)
			(layers "F.Cu" "F.Mask" "F.Paste")
			(net "GND")
		)
	)
	(footprint ""
		(layer "F.Cu")
		(at 355.227128 -258.726686 90)
		(property "Reference" "C970"
			(at 0 0 90)
			(layer "F.SilkS")
			(hide yes)
			(effects
				(font
					(size 1.27 1.27)
				)
			)
		)
		(property "Value" ""
			(at 0 0 90)
			(layer "F.Fab")
			(effects
				(font
					(size 1.27 1.27)
				)
			)
		)
		(duplicate_pad_numbers_are_jumpers no)
		(fp_line
			(start 0.7874 -0.4064)
			(end 0.7874 0.4064)
			(stroke
				(width 0.1524)
				(type default)
			)
			(layer "F.SilkS")
		)
		(fp_line
			(start -0.7874 -0.4064)
			(end 0.7874 -0.4064)
			(stroke
				(width 0.1524)
				(type default)
			)
			(layer "F.SilkS")
		)
		(fp_line
			(start 0.7874 0.4064)
			(end -0.7874 0.4064)
			(stroke
				(width 0.1524)
				(type default)
			)
			(layer "F.SilkS")
		)
		(fp_line
			(start -0.7874 0.4064)
			(end -0.7874 -0.4064)
			(stroke
				(width 0.1524)
				(type default)
			)
			(layer "F.SilkS")
		)
		(fp_line
			(start -0.12065 -0.305054)
			(end -0.12065 -0.2794)
			(stroke
				(width 0.1)
				(type default)
			)
			(layer "F.Fab")
		)
		(fp_line
			(start -0.67945 -0.305054)
			(end -0.12065 -0.305054)
			(stroke
				(width 0.1)
				(type default)
			)
			(layer "F.Fab")
		)
		(fp_line
			(start 0.67945 -0.3048)
			(end 0.67945 0.3048)
			(stroke
				(width 0.1)
				(type default)
			)
			(layer "F.Fab")
		)
		(fp_line
			(start 0.12065 -0.3048)
			(end 0.67945 -0.3048)
			(stroke
				(width 0.1)
				(type default)
			)
			(layer "F.Fab")
		)
		(fp_line
			(start 0.12065 -0.2794)
			(end 0.12065 -0.3048)
			(stroke
				(width 0.1)
				(type default)
			)
			(layer "F.Fab")
		)
		(fp_line
			(start -0.12065 -0.2794)
			(end 0.12065 -0.2794)
			(stroke
				(width 0.1)
				(type default)
			)
			(layer "F.Fab")
		)
		(fp_line
			(start 0.120396 0.2794)
			(end -0.12065 0.2794)
			(stroke
				(width 0.1)
				(type default)
			)
			(layer "F.Fab")
		)
		(fp_line
			(start -0.12065 0.2794)
			(end -0.12065 0.3048)
			(stroke
				(width 0.1)
				(type default)
			)
			(layer "F.Fab")
		)
		(fp_line
			(start 0.67945 0.3048)
			(end 0.120396 0.3048)
			(stroke
				(width 0.1)
				(type default)
			)
			(layer "F.Fab")
		)
		(fp_line
			(start 0.120396 0.3048)
			(end 0.120396 0.2794)
			(stroke
				(width 0.1)
				(type default)
			)
			(layer "F.Fab")
		)
		(fp_line
			(start -0.12065 0.3048)
			(end -0.67945 0.3048)
			(stroke
				(width 0.1)
				(type default)
			)
			(layer "F.Fab")
		)
		(fp_line
			(start -0.67945 0.3048)
			(end -0.67945 -0.305054)
			(stroke
				(width 0.1)
				(type default)
			)
			(layer "F.Fab")
		)
		(pad "1" smd circle
			(at -0.40005 0 90)
			(size 0 0)
			(layers "F.Cu" "F.Mask" "F.Paste")
			(net "PVCCIN_CPU0")
		)
		(pad "2" smd circle
			(at 0.40005 0 90)
			(size 0 0)
			(layers "F.Cu" "F.Mask" "F.Paste")
			(net "GND")
		)
	)
	(footprint ""
		(layer "F.Cu")
		(at 400.558 -170.983148)
		(property "Reference" "PC1576"
			(at 0 0 0)
			(layer "F.SilkS")
			(hide yes)
			(effects
				(font
					(size 1.27 1.27)
				)
			)
		)
		(property "Value" ""
			(at 0 0 0)
			(layer "F.Fab")
			(effects
				(font
					(size 1.27 1.27)
				)
			)
		)
		(duplicate_pad_numbers_are_jumpers no)
		(fp_line
			(start 2.750058 0.999998)
			(end -2.750058 0.999998)
			(stroke
				(width 0.1524)
				(type default)
			)
			(layer "F.SilkS")
		)
		(fp_circle
			(center 0 0.999998)
			(end 2.750058 0.999998)
			(stroke
				(width 0.1524)
				(type default)
			)
			(fill no)
			(layer "F.SilkS")
		)
		(fp_poly
			(pts
				(arc
					(start 2.750058 0.999998)
					(mid 0 3.750056)
					(end -2.750058 0.999998)
				)
			)
			(stroke
				(width 0)
				(type default)
			)
			(fill yes)
			(layer "F.SilkS")
		)
		(fp_circle
			(center 0 0.999998)
			(end 2.750058 0.999998)
			(stroke
				(width 0.1)
				(type default)
			)
			(fill no)
			(layer "F.Fab")
		)
		(pad "1" thru_hole rect
			(at 0 0)
			(size 1.5748 1.5748)
			(drill 1.0668)
			(layers "*.Cu" "*.Mask")
			(remove_unused_layers no)
			(net "PVCCINFAON_CPU0")
			(clearance 0)
			(padstack
				(mode front_inner_back)
				(layer "Inner"
					(shape circle)
					(size 1.5748 1.5748)
					(clearance 0)
				)
				(layer "B.Cu"
					(shape rect)
					(size 1.5748 1.5748)
					(clearance 0)
				)
			)
		)
		(pad "2" thru_hole circle
			(at 0 1.999996)
			(size 1.5748 1.5748)
			(drill 1.0668)
			(layers "*.Cu" "*.Mask")
			(remove_unused_layers no)
			(net "GND")
			(clearance 0)
		)
	)
	(footprint ""
		(layer "F.Cu")
		(at 259.021326 -130.193796)
		(property "Reference" "R4498"
			(at 0 0 0)
			(layer "F.SilkS")
			(hide yes)
			(effects
				(font
					(size 1.27 1.27)
				)
			)
		)
		(property "Value" ""
			(at 0 0 0)
			(layer "F.Fab")
			(effects
				(font
					(size 1.27 1.27)
				)
			)
		)
		(duplicate_pad_numbers_are_jumpers no)
		(fp_line
			(start -0.7874 -0.4064)
			(end 0.7874 -0.4064)
			(stroke
				(width 0.1524)
				(type default)
			)
			(layer "F.SilkS")
		)
		(fp_line
			(start -0.7874 0.4064)
			(end -0.7874 -0.4064)
			(stroke
				(width 0.1524)
				(type default)
			)
			(layer "F.SilkS")
		)
		(fp_line
			(start 0.7874 -0.4064)
			(end 0.7874 0.4064)
			(stroke
				(width 0.1524)
				(type default)
			)
			(layer "F.SilkS")
		)
		(fp_line
			(start 0.7874 0.4064)
			(end -0.7874 0.4064)
			(stroke
				(width 0.1524)
				(type default)
			)
			(layer "F.SilkS")
		)
		(fp_line
			(start -0.67945 -0.305054)
			(end -0.12065 -0.305054)
			(stroke
				(width 0.1)
				(type default)
			)
			(layer "F.Fab")
		)
		(fp_line
			(start -0.67945 0.3048)
			(end -0.67945 -0.305054)
			(stroke
				(width 0.1)
				(type default)
			)
			(layer "F.Fab")
		)
		(fp_line
			(start -0.12065 -0.305054)
			(end -0.12065 -0.2794)
			(stroke
				(width 0.1)
				(type default)
			)
			(layer "F.Fab")
		)
		(fp_line
			(start -0.12065 -0.2794)
			(end 0.12065 -0.2794)
			(stroke
				(width 0.1)
				(type default)
			)
			(layer "F.Fab")
		)
		(fp_line
			(start -0.12065 0.2794)
			(end -0.12065 0.3048)
			(stroke
				(width 0.1)
				(type default)
			)
			(layer "F.Fab")
		)
		(fp_line
			(start -0.12065 0.3048)
			(end -0.67945 0.3048)
			(stroke
				(width 0.1)
				(type default)
			)
			(layer "F.Fab")
		)
		(fp_line
			(start 0.120396 0.2794)
			(end -0.12065 0.2794)
			(stroke
				(width 0.1)
				(type default)
			)
			(layer "F.Fab")
		)
		(fp_line
			(start 0.120396 0.3048)
			(end 0.120396 0.2794)
			(stroke
				(width 0.1)
				(type default)
			)
			(layer "F.Fab")
		)
		(fp_line
			(start 0.12065 -0.3048)
			(end 0.67945 -0.3048)
			(stroke
				(width 0.1)
				(type default)
			)
			(layer "F.Fab")
		)
		(fp_line
			(start 0.12065 -0.2794)
			(end 0.12065 -0.3048)
			(stroke
				(width 0.1)
				(type default)
			)
			(layer "F.Fab")
		)
		(fp_line
			(start 0.67945 -0.3048)
			(end 0.67945 0.3048)
			(stroke
				(width 0.1)
				(type default)
			)
			(layer "F.Fab")
		)
		(fp_line
			(start 0.67945 0.3048)
			(end 0.120396 0.3048)
			(stroke
				(width 0.1)
				(type default)
			)
			(layer "F.Fab")
		)
		(pad "1" smd circle
			(at -0.40005 0)
			(size 0 0)
			(layers "F.Cu" "F.Mask" "F.Paste")
			(net "P3V3")
		)
		(pad "2" smd circle
			(at 0.40005 0)
			(size 0 0)
			(layers "F.Cu" "F.Mask" "F.Paste")
			(net "SMB_HOST_CLK_BUF_ISO_3V3AUX_S_1")
		)
	)
	(footprint ""
		(layer "F.Cu")
		(at 153.60015 -70.26402 -90)
		(property "Reference" "R2309"
			(at 0 0 270)
			(layer "F.SilkS")
			(hide yes)
			(effects
				(font
					(size 1.27 1.27)
				)
			)
		)
		(property "Value" ""
			(at 0 0 270)
			(layer "F.Fab")
			(effects
				(font
					(size 1.27 1.27)
				)
			)
		)
		(duplicate_pad_numbers_are_jumpers no)
		(fp_line
			(start -0.7874 0.4064)
			(end -0.7874 -0.4064)
			(stroke
				(width 0.1524)
				(type default)
			)
			(layer "F.SilkS")
		)
		(fp_line
			(start 0.7874 0.4064)
			(end -0.7874 0.4064)
			(stroke
				(width 0.1524)
				(type default)
			)
			(layer "F.SilkS")
		)
		(fp_line
			(start -0.7874 -0.4064)
			(end 0.7874 -0.4064)
			(stroke
				(width 0.1524)
				(type default)
			)
			(layer "F.SilkS")
		)
		(fp_line
			(start 0.7874 -0.4064)
			(end 0.7874 0.4064)
			(stroke
				(width 0.1524)
				(type default)
			)
			(layer "F.SilkS")
		)
		(fp_line
			(start -0.67945 0.3048)
			(end -0.67945 -0.305054)
			(stroke
				(width 0.1)
				(type default)
			)
			(layer "F.Fab")
		)
		(fp_line
			(start -0.12065 0.3048)
			(end -0.67945 0.3048)
			(stroke
				(width 0.1)
				(type default)
			)
			(layer "F.Fab")
		)
		(fp_line
			(start 0.120396 0.3048)
			(end 0.120396 0.2794)
			(stroke
				(width 0.1)
				(type default)
			)
			(layer "F.Fab")
		)
		(fp_line
			(start 0.67945 0.3048)
			(end 0.120396 0.3048)
			(stroke
				(width 0.1)
				(type default)
			)
			(layer "F.Fab")
		)
		(fp_line
			(start -0.12065 0.2794)
			(end -0.12065 0.3048)
			(stroke
				(width 0.1)
				(type default)
			)
			(layer "F.Fab")
		)
		(fp_line
			(start 0.120396 0.2794)
			(end -0.12065 0.2794)
			(stroke
				(width 0.1)
				(type default)
			)
			(layer "F.Fab")
		)
		(fp_line
			(start -0.12065 -0.2794)
			(end 0.12065 -0.2794)
			(stroke
				(width 0.1)
				(type default)
			)
			(layer "F.Fab")
		)
		(fp_line
			(start 0.12065 -0.2794)
			(end 0.12065 -0.3048)
			(stroke
				(width 0.1)
				(type default)
			)
			(layer "F.Fab")
		)
		(fp_line
			(start 0.12065 -0.3048)
			(end 0.67945 -0.3048)
			(stroke
				(width 0.1)
				(type default)
			)
			(layer "F.Fab")
		)
		(fp_line
			(start 0.67945 -0.3048)
			(end 0.67945 0.3048)
			(stroke
				(width 0.1)
				(type default)
			)
			(layer "F.Fab")
		)
		(fp_line
			(start -0.67945 -0.305054)
			(end -0.12065 -0.305054)
			(stroke
				(width 0.1)
				(type default)
			)
			(layer "F.Fab")
		)
		(fp_line
			(start -0.12065 -0.305054)
			(end -0.12065 -0.2794)
			(stroke
				(width 0.1)
				(type default)
			)
			(layer "F.Fab")
		)
		(pad "1" smd circle
			(at -0.40005 0 270)
			(size 0 0)
			(layers "F.Cu" "F.Mask" "F.Paste")
			(net "PCA9543_S3M_ADDR1")
		)
		(pad "2" smd circle
			(at 0.40005 0 270)
			(size 0 0)
			(layers "F.Cu" "F.Mask" "F.Paste")
			(net "GND")
		)
	)
	(footprint ""
		(layer "F.Cu")
		(at 225.125788 -222.09887)
		(property "Reference" "R970"
			(at 0 0 0)
			(layer "F.SilkS")
			(hide yes)
			(effects
				(font
					(size 1.27 1.27)
				)
			)
		)
		(property "Value" ""
			(at 0 0 0)
			(layer "F.Fab")
			(effects
				(font
					(size 1.27 1.27)
				)
			)
		)
		(duplicate_pad_numbers_are_jumpers no)
		(fp_line
			(start -0.7874 -0.4064)
			(end 0.7874 -0.4064)
			(stroke
				(width 0.1524)
				(type default)
			)
			(layer "F.SilkS")
		)
		(fp_line
			(start -0.7874 0.4064)
			(end -0.7874 -0.4064)
			(stroke
				(width 0.1524)
				(type default)
			)
			(layer "F.SilkS")
		)
		(fp_line
			(start 0.7874 -0.4064)
			(end 0.7874 0.4064)
			(stroke
				(width 0.1524)
				(type default)
			)
			(layer "F.SilkS")
		)
		(fp_line
			(start 0.7874 0.4064)
			(end -0.7874 0.4064)
			(stroke
				(width 0.1524)
				(type default)
			)
			(layer "F.SilkS")
		)
		(fp_line
			(start -0.67945 -0.305054)
			(end -0.12065 -0.305054)
			(stroke
				(width 0.1)
				(type default)
			)
			(layer "F.Fab")
		)
		(fp_line
			(start -0.67945 0.3048)
			(end -0.67945 -0.305054)
			(stroke
				(width 0.1)
				(type default)
			)
			(layer "F.Fab")
		)
		(fp_line
			(start -0.12065 -0.305054)
			(end -0.12065 -0.2794)
			(stroke
				(width 0.1)
				(type default)
			)
			(layer "F.Fab")
		)
		(fp_line
			(start -0.12065 -0.2794)
			(end 0.12065 -0.2794)
			(stroke
				(width 0.1)
				(type default)
			)
			(layer "F.Fab")
		)
		(fp_line
			(start -0.12065 0.2794)
			(end -0.12065 0.3048)
			(stroke
				(width 0.1)
				(type default)
			)
			(layer "F.Fab")
		)
		(fp_line
			(start -0.12065 0.3048)
			(end -0.67945 0.3048)
			(stroke
				(width 0.1)
				(type default)
			)
			(layer "F.Fab")
		)
		(fp_line
			(start 0.120396 0.2794)
			(end -0.12065 0.2794)
			(stroke
				(width 0.1)
				(type default)
			)
			(layer "F.Fab")
		)
		(fp_line
			(start 0.120396 0.3048)
			(end 0.120396 0.2794)
			(stroke
				(width 0.1)
				(type default)
			)
			(layer "F.Fab")
		)
		(fp_line
			(start 0.12065 -0.3048)
			(end 0.67945 -0.3048)
			(stroke
				(width 0.1)
				(type default)
			)
			(layer "F.Fab")
		)
		(fp_line
			(start 0.12065 -0.2794)
			(end 0.12065 -0.3048)
			(stroke
				(width 0.1)
				(type default)
			)
			(layer "F.Fab")
		)
		(fp_line
			(start 0.67945 -0.3048)
			(end 0.67945 0.3048)
			(stroke
				(width 0.1)
				(type default)
			)
			(layer "F.Fab")
		)
		(fp_line
			(start 0.67945 0.3048)
			(end 0.120396 0.3048)
			(stroke
				(width 0.1)
				(type default)
			)
			(layer "F.Fab")
		)
		(pad "1" smd circle
			(at -0.40005 0)
			(size 0 0)
			(layers "F.Cu" "F.Mask" "F.Paste")
			(net "PVNN_TERM_CPU1")
		)
		(pad "2" smd circle
			(at 0.40005 0)
			(size 0 0)
			(layers "F.Cu" "F.Mask" "F.Paste")
			(net "SMB_S3M_CPU1_R_SCL")
		)
	)
)
